(kicad_pcb
	(version 20260206)
	(generator "pcbnew")
	(generator_version "10.0")
	(general
		(thickness 1.6)
		(legacy_teardrops no)
	)
	(paper "A4")
	(title_block
		(title "03242023_DA0F0TMBIJ0_F0T_Motherboard_J_brd_V01_OCP.brd")
		(comment 1 "Grand Teton / footprints 3940-3946 of 6105")
	)
	(layers
		(0 "F.Cu" signal "TOP")
		(4 "In1.Cu" signal "GND")
		(6 "In2.Cu" signal "IN1")
		(8 "In3.Cu" signal "GND1")
		(10 "In4.Cu" signal "IN2")
		(12 "In5.Cu" signal "GND2")
		(14 "In6.Cu" signal "IN3")
		(16 "In7.Cu" signal "GND3")
		(18 "In8.Cu" signal "VCC")
		(20 "In9.Cu" signal "VCC1")
		(22 "In10.Cu" signal "GND4")
		(24 "In11.Cu" signal "IN4")
		(26 "In12.Cu" signal "GND5")
		(28 "In13.Cu" signal "IN5")
		(30 "In14.Cu" signal "GND6")
		(32 "In15.Cu" signal "IN6")
		(34 "In16.Cu" signal "GND7")
		(2 "B.Cu" signal "BOTTOM")
		(9 "F.Adhes" user "F.Adhesive")
		(11 "B.Adhes" user "B.Adhesive")
		(13 "F.Paste" user "Package Geometry/Pastemask Top")
		(15 "B.Paste" user "Package Geometry/Pastemask Bottom")
		(5 "F.SilkS" user "Ref Des/Silkscreen Top")
		(7 "B.SilkS" user "Ref Des/Silkscreen Bottom")
		(1 "F.Mask" user "Board Geometry/Soldermask Top")
		(3 "B.Mask" user "Board Geometry/Soldermask Bottom")
		(17 "Dwgs.User" user "User.Drawings")
		(19 "Cmts.User" user "User.Comments")
		(21 "Eco1.User" user "User.Eco1")
		(23 "Eco2.User" user "User.Eco2")
		(25 "Edge.Cuts" user "Board Geometry/Outline")
		(27 "Margin" user)
		(31 "F.CrtYd" user "Package Geometry/Place Bound Top")
		(29 "B.CrtYd" user "Package Geometry/Place Bound Bottom")
		(35 "F.Fab" user "Ref Des/Assembly Top")
		(33 "B.Fab" user "Ref Des/Assembly Bottom")
	)
	(footprint ""
		(layer "F.Cu")
		(at 24.050752 -405.858218)
		(property "Reference" "R3439"
			(at 0 0 0)
			(layer "F.SilkS")
			(hide yes)
			(effects
				(font
					(size 1.27 1.27)
				)
			)
		)
		(property "Value" ""
			(at 0 0 0)
			(layer "F.Fab")
			(effects
				(font
					(size 1.27 1.27)
				)
			)
		)
		(duplicate_pad_numbers_are_jumpers no)
		(fp_line
			(start -0.7874 -0.4064)
			(end 0.7874 -0.4064)
			(stroke
				(width 0.1524)
				(type default)
			)
			(layer "F.SilkS")
		)
		(fp_line
			(start -0.7874 0.4064)
			(end -0.7874 -0.4064)
			(stroke
				(width 0.1524)
				(type default)
			)
			(layer "F.SilkS")
		)
		(fp_line
			(start 0.7874 -0.4064)
			(end 0.7874 0.4064)
			(stroke
				(width 0.1524)
				(type default)
			)
			(layer "F.SilkS")
		)
		(fp_line
			(start 0.7874 0.4064)
			(end -0.7874 0.4064)
			(stroke
				(width 0.1524)
				(type default)
			)
			(layer "F.SilkS")
		)
		(fp_line
			(start -0.67945 -0.305054)
			(end -0.12065 -0.305054)
			(stroke
				(width 0.1)
				(type default)
			)
			(layer "F.Fab")
		)
		(fp_line
			(start -0.67945 0.3048)
			(end -0.67945 -0.305054)
			(stroke
				(width 0.1)
				(type default)
			)
			(layer "F.Fab")
		)
		(fp_line
			(start -0.12065 -0.305054)
			(end -0.12065 -0.2794)
			(stroke
				(width 0.1)
				(type default)
			)
			(layer "F.Fab")
		)
		(fp_line
			(start -0.12065 -0.2794)
			(end 0.12065 -0.2794)
			(stroke
				(width 0.1)
				(type default)
			)
			(layer "F.Fab")
		)
		(fp_line
			(start -0.12065 0.2794)
			(end -0.12065 0.3048)
			(stroke
				(width 0.1)
				(type default)
			)
			(layer "F.Fab")
		)
		(fp_line
			(start -0.12065 0.3048)
			(end -0.67945 0.3048)
			(stroke
				(width 0.1)
				(type default)
			)
			(layer "F.Fab")
		)
		(fp_line
			(start 0.120396 0.2794)
			(end -0.12065 0.2794)
			(stroke
				(width 0.1)
				(type default)
			)
			(layer "F.Fab")
		)
		(fp_line
			(start 0.120396 0.3048)
			(end 0.120396 0.2794)
			(stroke
				(width 0.1)
				(type default)
			)
			(layer "F.Fab")
		)
		(fp_line
			(start 0.12065 -0.3048)
			(end 0.67945 -0.3048)
			(stroke
				(width 0.1)
				(type default)
			)
			(layer "F.Fab")
		)
		(fp_line
			(start 0.12065 -0.2794)
			(end 0.12065 -0.3048)
			(stroke
				(width 0.1)
				(type default)
			)
			(layer "F.Fab")
		)
		(fp_line
			(start 0.67945 -0.3048)
			(end 0.67945 0.3048)
			(stroke
				(width 0.1)
				(type default)
			)
			(layer "F.Fab")
		)
		(fp_line
			(start 0.67945 0.3048)
			(end 0.120396 0.3048)
			(stroke
				(width 0.1)
				(type default)
			)
			(layer "F.Fab")
		)
		(pad "1" smd circle
			(at -0.40005 0)
			(size 0 0)
			(layers "F.Cu" "F.Mask" "F.Paste")
			(net "P3V3_AUX")
		)
		(pad "2" smd circle
			(at 0.40005 0)
			(size 0 0)
			(layers "F.Cu" "F.Mask" "F.Paste")
			(net "GPU_FPGA_THERM_OVERT_ISO_N")
		)
	)
	(footprint ""
		(layer "F.Cu")
		(at 304.53965 -62.151768 180)
		(property "Reference" "R2255"
			(at 0 0 180)
			(layer "F.SilkS")
			(hide yes)
			(effects
				(font
					(size 1.27 1.27)
				)
			)
		)
		(property "Value" ""
			(at 0 0 180)
			(layer "F.Fab")
			(effects
				(font
					(size 1.27 1.27)
				)
			)
		)
		(duplicate_pad_numbers_are_jumpers no)
		(fp_line
			(start 0.7874 0.4064)
			(end -0.7874 0.4064)
			(stroke
				(width 0.1524)
				(type default)
			)
			(layer "F.SilkS")
		)
		(fp_line
			(start 0.7874 -0.4064)
			(end 0.7874 0.4064)
			(stroke
				(width 0.1524)
				(type default)
			)
			(layer "F.SilkS")
		)
		(fp_line
			(start -0.7874 0.4064)
			(end -0.7874 -0.4064)
			(stroke
				(width 0.1524)
				(type default)
			)
			(layer "F.SilkS")
		)
		(fp_line
			(start -0.7874 -0.4064)
			(end 0.7874 -0.4064)
			(stroke
				(width 0.1524)
				(type default)
			)
			(layer "F.SilkS")
		)
		(fp_line
			(start 0.67945 0.3048)
			(end 0.120396 0.3048)
			(stroke
				(width 0.1)
				(type default)
			)
			(layer "F.Fab")
		)
		(fp_line
			(start 0.67945 -0.3048)
			(end 0.67945 0.3048)
			(stroke
				(width 0.1)
				(type default)
			)
			(layer "F.Fab")
		)
		(fp_line
			(start 0.12065 -0.2794)
			(end 0.12065 -0.3048)
			(stroke
				(width 0.1)
				(type default)
			)
			(layer "F.Fab")
		)
		(fp_line
			(start 0.12065 -0.3048)
			(end 0.67945 -0.3048)
			(stroke
				(width 0.1)
				(type default)
			)
			(layer "F.Fab")
		)
		(fp_line
			(start 0.120396 0.3048)
			(end 0.120396 0.2794)
			(stroke
				(width 0.1)
				(type default)
			)
			(layer "F.Fab")
		)
		(fp_line
			(start 0.120396 0.2794)
			(end -0.12065 0.2794)
			(stroke
				(width 0.1)
				(type default)
			)
			(layer "F.Fab")
		)
		(fp_line
			(start -0.12065 0.3048)
			(end -0.67945 0.3048)
			(stroke
				(width 0.1)
				(type default)
			)
			(layer "F.Fab")
		)
		(fp_line
			(start -0.12065 0.2794)
			(end -0.12065 0.3048)
			(stroke
				(width 0.1)
				(type default)
			)
			(layer "F.Fab")
		)
		(fp_line
			(start -0.12065 -0.2794)
			(end 0.12065 -0.2794)
			(stroke
				(width 0.1)
				(type default)
			)
			(layer "F.Fab")
		)
		(fp_line
			(start -0.12065 -0.305054)
			(end -0.12065 -0.2794)
			(stroke
				(width 0.1)
				(type default)
			)
			(layer "F.Fab")
		)
		(fp_line
			(start -0.67945 0.3048)
			(end -0.67945 -0.305054)
			(stroke
				(width 0.1)
				(type default)
			)
			(layer "F.Fab")
		)
		(fp_line
			(start -0.67945 -0.305054)
			(end -0.12065 -0.305054)
			(stroke
				(width 0.1)
				(type default)
			)
			(layer "F.Fab")
		)
		(pad "1" smd circle
			(at -0.40005 0 180)
			(size 0 0)
			(layers "F.Cu" "F.Mask" "F.Paste")
			(net "PECI_MUX_SEL_R")
		)
		(pad "2" smd circle
			(at 0.40005 0 180)
			(size 0 0)
			(layers "F.Cu" "F.Mask" "F.Paste")
			(net "FM_PECI_MUX_SEL_N")
		)
	)
	(footprint ""
		(layer "F.Cu")
		(at 98.33864 -30.434788 180)
		(property "Reference" "C1861"
			(at 0 0 180)
			(layer "F.SilkS")
			(hide yes)
			(effects
				(font
					(size 1.27 1.27)
				)
			)
		)
		(property "Value" ""
			(at 0 0 180)
			(layer "F.Fab")
			(effects
				(font
					(size 1.27 1.27)
				)
			)
		)
		(duplicate_pad_numbers_are_jumpers no)
		(fp_line
			(start 0.7874 0.4064)
			(end -0.7874 0.4064)
			(stroke
				(width 0.1524)
				(type default)
			)
			(layer "F.SilkS")
		)
		(fp_line
			(start 0.7874 -0.4064)
			(end 0.7874 0.4064)
			(stroke
				(width 0.1524)
				(type default)
			)
			(layer "F.SilkS")
		)
		(fp_line
			(start -0.7874 0.4064)
			(end -0.7874 -0.4064)
			(stroke
				(width 0.1524)
				(type default)
			)
			(layer "F.SilkS")
		)
		(fp_line
			(start -0.7874 -0.4064)
			(end 0.7874 -0.4064)
			(stroke
				(width 0.1524)
				(type default)
			)
			(layer "F.SilkS")
		)
		(fp_line
			(start 0.67945 0.3048)
			(end 0.120396 0.3048)
			(stroke
				(width 0.1)
				(type default)
			)
			(layer "F.Fab")
		)
		(fp_line
			(start 0.67945 -0.3048)
			(end 0.67945 0.3048)
			(stroke
				(width 0.1)
				(type default)
			)
			(layer "F.Fab")
		)
		(fp_line
			(start 0.12065 -0.2794)
			(end 0.12065 -0.3048)
			(stroke
				(width 0.1)
				(type default)
			)
			(layer "F.Fab")
		)
		(fp_line
			(start 0.12065 -0.3048)
			(end 0.67945 -0.3048)
			(stroke
				(width 0.1)
				(type default)
			)
			(layer "F.Fab")
		)
		(fp_line
			(start 0.120396 0.3048)
			(end 0.120396 0.2794)
			(stroke
				(width 0.1)
				(type default)
			)
			(layer "F.Fab")
		)
		(fp_line
			(start 0.120396 0.2794)
			(end -0.12065 0.2794)
			(stroke
				(width 0.1)
				(type default)
			)
			(layer "F.Fab")
		)
		(fp_line
			(start -0.12065 0.3048)
			(end -0.67945 0.3048)
			(stroke
				(width 0.1)
				(type default)
			)
			(layer "F.Fab")
		)
		(fp_line
			(start -0.12065 0.2794)
			(end -0.12065 0.3048)
			(stroke
				(width 0.1)
				(type default)
			)
			(layer "F.Fab")
		)
		(fp_line
			(start -0.12065 -0.2794)
			(end 0.12065 -0.2794)
			(stroke
				(width 0.1)
				(type default)
			)
			(layer "F.Fab")
		)
		(fp_line
			(start -0.12065 -0.305054)
			(end -0.12065 -0.2794)
			(stroke
				(width 0.1)
				(type default)
			)
			(layer "F.Fab")
		)
		(fp_line
			(start -0.67945 0.3048)
			(end -0.67945 -0.305054)
			(stroke
				(width 0.1)
				(type default)
			)
			(layer "F.Fab")
		)
		(fp_line
			(start -0.67945 -0.305054)
			(end -0.12065 -0.305054)
			(stroke
				(width 0.1)
				(type default)
			)
			(layer "F.Fab")
		)
		(pad "1" smd circle
			(at -0.40005 0 180)
			(size 0 0)
			(layers "F.Cu" "F.Mask" "F.Paste")
			(net "P3V3_OCP_V3_2")
		)
		(pad "2" smd circle
			(at 0.40005 0 180)
			(size 0 0)
			(layers "F.Cu" "F.Mask" "F.Paste")
			(net "GND")
		)
	)
	(footprint ""
		(layer "F.Cu")
		(at 366.431322 -425.18457)
		(property "Reference" "R4183"
			(at 0 0 0)
			(layer "F.SilkS")
			(hide yes)
			(effects
				(font
					(size 1.27 1.27)
				)
			)
		)
		(property "Value" ""
			(at 0 0 0)
			(layer "F.Fab")
			(effects
				(font
					(size 1.27 1.27)
				)
			)
		)
		(duplicate_pad_numbers_are_jumpers no)
		(fp_line
			(start -0.7874 -0.4064)
			(end 0.7874 -0.4064)
			(stroke
				(width 0.1524)
				(type default)
			)
			(layer "F.SilkS")
		)
		(fp_line
			(start -0.7874 0.4064)
			(end -0.7874 -0.4064)
			(stroke
				(width 0.1524)
				(type default)
			)
			(layer "F.SilkS")
		)
		(fp_line
			(start 0.7874 -0.4064)
			(end 0.7874 0.4064)
			(stroke
				(width 0.1524)
				(type default)
			)
			(layer "F.SilkS")
		)
		(fp_line
			(start 0.7874 0.4064)
			(end -0.7874 0.4064)
			(stroke
				(width 0.1524)
				(type default)
			)
			(layer "F.SilkS")
		)
		(fp_line
			(start -0.67945 -0.305054)
			(end -0.12065 -0.305054)
			(stroke
				(width 0.1)
				(type default)
			)
			(layer "F.Fab")
		)
		(fp_line
			(start -0.67945 0.3048)
			(end -0.67945 -0.305054)
			(stroke
				(width 0.1)
				(type default)
			)
			(layer "F.Fab")
		)
		(fp_line
			(start -0.12065 -0.305054)
			(end -0.12065 -0.2794)
			(stroke
				(width 0.1)
				(type default)
			)
			(layer "F.Fab")
		)
		(fp_line
			(start -0.12065 -0.2794)
			(end 0.12065 -0.2794)
			(stroke
				(width 0.1)
				(type default)
			)
			(layer "F.Fab")
		)
		(fp_line
			(start -0.12065 0.2794)
			(end -0.12065 0.3048)
			(stroke
				(width 0.1)
				(type default)
			)
			(layer "F.Fab")
		)
		(fp_line
			(start -0.12065 0.3048)
			(end -0.67945 0.3048)
			(stroke
				(width 0.1)
				(type default)
			)
			(layer "F.Fab")
		)
		(fp_line
			(start 0.120396 0.2794)
			(end -0.12065 0.2794)
			(stroke
				(width 0.1)
				(type default)
			)
			(layer "F.Fab")
		)
		(fp_line
			(start 0.120396 0.3048)
			(end 0.120396 0.2794)
			(stroke
				(width 0.1)
				(type default)
			)
			(layer "F.Fab")
		)
		(fp_line
			(start 0.12065 -0.3048)
			(end 0.67945 -0.3048)
			(stroke
				(width 0.1)
				(type default)
			)
			(layer "F.Fab")
		)
		(fp_line
			(start 0.12065 -0.2794)
			(end 0.12065 -0.3048)
			(stroke
				(width 0.1)
				(type default)
			)
			(layer "F.Fab")
		)
		(fp_line
			(start 0.67945 -0.3048)
			(end 0.67945 0.3048)
			(stroke
				(width 0.1)
				(type default)
			)
			(layer "F.Fab")
		)
		(fp_line
			(start 0.67945 0.3048)
			(end 0.120396 0.3048)
			(stroke
				(width 0.1)
				(type default)
			)
			(layer "F.Fab")
		)
		(pad "1" smd circle
			(at -0.40005 0)
			(size 0 0)
			(layers "F.Cu" "F.Mask" "F.Paste")
			(net "SMB_LM75_0_3V3AUX_SDA")
		)
		(pad "2" smd circle
			(at 0.40005 0)
			(size 0 0)
			(layers "F.Cu" "F.Mask" "F.Paste")
			(net "SMB_LM75_0_3V3AUX_SDA_R1")
		)
	)
	(footprint ""
		(layer "F.Cu")
		(at 100.66655 -359.059226)
		(property "Reference" "R2525"
			(at 0 0 0)
			(layer "F.SilkS")
			(hide yes)
			(effects
				(font
					(size 1.27 1.27)
				)
			)
		)
		(property "Value" ""
			(at 0 0 0)
			(layer "F.Fab")
			(effects
				(font
					(size 1.27 1.27)
				)
			)
		)
		(duplicate_pad_numbers_are_jumpers no)
		(fp_line
			(start -0.7874 -0.4064)
			(end 0.7874 -0.4064)
			(stroke
				(width 0.1524)
				(type default)
			)
			(layer "F.SilkS")
		)
		(fp_line
			(start -0.7874 0.4064)
			(end -0.7874 -0.4064)
			(stroke
				(width 0.1524)
				(type default)
			)
			(layer "F.SilkS")
		)
		(fp_line
			(start 0.7874 -0.4064)
			(end 0.7874 0.4064)
			(stroke
				(width 0.1524)
				(type default)
			)
			(layer "F.SilkS")
		)
		(fp_line
			(start 0.7874 0.4064)
			(end -0.7874 0.4064)
			(stroke
				(width 0.1524)
				(type default)
			)
			(layer "F.SilkS")
		)
		(fp_line
			(start -0.67945 -0.305054)
			(end -0.12065 -0.305054)
			(stroke
				(width 0.1)
				(type default)
			)
			(layer "F.Fab")
		)
		(fp_line
			(start -0.67945 0.3048)
			(end -0.67945 -0.305054)
			(stroke
				(width 0.1)
				(type default)
			)
			(layer "F.Fab")
		)
		(fp_line
			(start -0.12065 -0.305054)
			(end -0.12065 -0.2794)
			(stroke
				(width 0.1)
				(type default)
			)
			(layer "F.Fab")
		)
		(fp_line
			(start -0.12065 -0.2794)
			(end 0.12065 -0.2794)
			(stroke
				(width 0.1)
				(type default)
			)
			(layer "F.Fab")
		)
		(fp_line
			(start -0.12065 0.2794)
			(end -0.12065 0.3048)
			(stroke
				(width 0.1)
				(type default)
			)
			(layer "F.Fab")
		)
		(fp_line
			(start -0.12065 0.3048)
			(end -0.67945 0.3048)
			(stroke
				(width 0.1)
				(type default)
			)
			(layer "F.Fab")
		)
		(fp_line
			(start 0.120396 0.2794)
			(end -0.12065 0.2794)
			(stroke
				(width 0.1)
				(type default)
			)
			(layer "F.Fab")
		)
		(fp_line
			(start 0.120396 0.3048)
			(end 0.120396 0.2794)
			(stroke
				(width 0.1)
				(type default)
			)
			(layer "F.Fab")
		)
		(fp_line
			(start 0.12065 -0.3048)
			(end 0.67945 -0.3048)
			(stroke
				(width 0.1)
				(type default)
			)
			(layer "F.Fab")
		)
		(fp_line
			(start 0.12065 -0.2794)
			(end 0.12065 -0.3048)
			(stroke
				(width 0.1)
				(type default)
			)
			(layer "F.Fab")
		)
		(fp_line
			(start 0.67945 -0.3048)
			(end 0.67945 0.3048)
			(stroke
				(width 0.1)
				(type default)
			)
			(layer "F.Fab")
		)
		(fp_line
			(start 0.67945 0.3048)
			(end 0.120396 0.3048)
			(stroke
				(width 0.1)
				(type default)
			)
			(layer "F.Fab")
		)
		(pad "1" smd circle
			(at -0.40005 0)
			(size 0 0)
			(layers "F.Cu" "F.Mask" "F.Paste")
			(net "P3V3_AUX")
		)
		(pad "2" smd circle
			(at 0.40005 0)
			(size 0 0)
			(layers "F.Cu" "F.Mask" "F.Paste")
			(net "PVCCIN_CPU1_PIN_ALERT")
		)
	)
	(footprint ""
		(layer "F.Cu")
		(at 311.427368 -408.517344 -90)
		(property "Reference" "C906"
			(at 0 0 270)
			(layer "F.SilkS")
			(hide yes)
			(effects
				(font
					(size 1.27 1.27)
				)
			)
		)
		(property "Value" ""
			(at 0 0 270)
			(layer "F.Fab")
			(effects
				(font
					(size 1.27 1.27)
				)
			)
		)
		(duplicate_pad_numbers_are_jumpers no)
		(fp_line
			(start -0.299974 0.150114)
			(end -0.299974 -0.150114)
			(stroke
				(width 0.1)
				(type default)
			)
			(layer "F.Fab")
		)
		(fp_line
			(start 0.299974 0.150114)
			(end -0.299974 0.150114)
			(stroke
				(width 0.1)
				(type default)
			)
			(layer "F.Fab")
		)
		(fp_line
			(start -0.299974 -0.150114)
			(end 0.299974 -0.150114)
			(stroke
				(width 0.1)
				(type default)
			)
			(layer "F.Fab")
		)
		(fp_line
			(start 0.299974 -0.150114)
			(end 0.299974 0.150114)
			(stroke
				(width 0.1)
				(type default)
			)
			(layer "F.Fab")
		)
		(pad "1" smd rect
			(at -0.2667 0 270)
			(size 0.3048 0.381)
			(layers "F.Cu" "F.Mask" "F.Paste")
			(net "P5E_CPU0_PE0_TX_C_DN<13>")
		)
		(pad "2" smd rect
			(at 0.2667 0 270)
			(size 0.3048 0.381)
			(layers "F.Cu" "F.Mask" "F.Paste")
			(net "P5E_CPU0_PE0_TX_DN<13>")
		)
	)
	(footprint ""
		(layer "F.Cu")
		(at 155.63596 -45.452538 -90)
		(property "Reference" "R4460"
			(at 0 0 270)
			(layer "F.SilkS")
			(hide yes)
			(effects
				(font
					(size 1.27 1.27)
				)
			)
		)
		(property "Value" ""
			(at 0 0 270)
			(layer "F.Fab")
			(effects
				(font
					(size 1.27 1.27)
				)
			)
		)
		(duplicate_pad_numbers_are_jumpers no)
		(fp_line
			(start 0.7874 0.4064)
			(end -0.7874 0.4064)
			(stroke
				(width 0.1524)
				(type default)
			)
			(layer "F.SilkS")
		)
		(fp_line
			(start 0.7874 -0.4064)
			(end 0.7874 0.4064)
			(stroke
				(width 0.1524)
				(type default)
			)
			(layer "F.SilkS")
		)
		(fp_line
			(start -0.67945 0.3048)
			(end -0.67945 -0.305054)
			(stroke
				(width 0.1)
				(type default)
			)
			(layer "F.Fab")
		)
		(fp_line
			(start -0.12065 0.3048)
			(end -0.67945 0.3048)
			(stroke
				(width 0.1)
				(type default)
			)
			(layer "F.Fab")
		)
		(fp_line
			(start 0.120396 0.3048)
			(end 0.120396 0.2794)
			(stroke
				(width 0.1)
				(type default)
			)
			(layer "F.Fab")
		)
		(fp_line
			(start 0.67945 0.3048)
			(end 0.120396 0.3048)
			(stroke
				(width 0.1)
				(type default)
			)
			(layer "F.Fab")
		)
		(fp_line
			(start -0.12065 0.2794)
			(end -0.12065 0.3048)
			(stroke
				(width 0.1)
				(type default)
			)
			(layer "F.Fab")
		)
		(fp_line
			(start 0.120396 0.2794)
			(end -0.12065 0.2794)
			(stroke
				(width 0.1)
				(type default)
			)
			(layer "F.Fab")
		)
		(fp_line
			(start -0.12065 -0.2794)
			(end 0.12065 -0.2794)
			(stroke
				(width 0.1)
				(type default)
			)
			(layer "F.Fab")
		)
		(fp_line
			(start 0.12065 -0.2794)
			(end 0.12065 -0.3048)
			(stroke
				(width 0.1)
				(type default)
			)
			(layer "F.Fab")
		)
		(fp_line
			(start 0.12065 -0.3048)
			(end 0.67945 -0.3048)
			(stroke
				(width 0.1)
				(type default)
			)
			(layer "F.Fab")
		)
		(fp_line
			(start 0.67945 -0.3048)
			(end 0.67945 0.3048)
			(stroke
				(width 0.1)
				(type default)
			)
			(layer "F.Fab")
		)
		(fp_line
			(start -0.67945 -0.305054)
			(end -0.12065 -0.305054)
			(stroke
				(width 0.1)
				(type default)
			)
			(layer "F.Fab")
		)
		(fp_line
			(start -0.12065 -0.305054)
			(end -0.12065 -0.2794)
			(stroke
				(width 0.1)
				(type default)
			)
			(layer "F.Fab")
		)
		(pad "1" smd rect
			(at -0.40005 0 90)
			(size 0.4572 0.508)
			(layers "F.Cu" "F.Mask" "F.Paste")
			(net "USB2_HOST_PCH_0_DP")
		)
		(pad "2" smd rect
			(at 0.40005 0 90)
			(size 0.4572 0.508)
			(layers "F.Cu" "F.Mask" "F.Paste")
			(net "USB2_HUB_2_BUF_EXT_R_DP")
		)
	)
)
